# T6G (Grand Teton) — schematic netlist excerpt (pin names and nets, part order shuffled) for the footprints in the layout excerpt that follows; sources: Cadence DE-HDL packaged netlist, KiCad conversion of 04192023_DAF0TMB3IC0_F0TG_MB_C_brd_V02_OCP.brd

J30  SCONN288_DDR506112002KQ  IO  pkg DDR288S_1-1VXC  page 101
  VIN_BULK0  = P12V_MEM_CPU1
  RFU0  = NC
  VIN_MGMT  = P3V3_AUX
  HSCL  = I3C_SPD_DDRD_CPU1_SCL
  HSDA  = I3C_SPD_DDRD_CPU1_SDA
  VSS0  = GND
  DQ0_A  = M_D_CPU1_SA_DQ<0>
  VSS1  = GND
  DQ1_A  = M_D_CPU1_SA_DQ<1>
  VSS2  = GND
  DQS0_A_T  = M_D_CPU1_SA_DQS_DP<0>
  DQS0_A_C  = M_D_CPU1_SA_DQS_DN<0>
  VSS3  = GND
  DQ4_A  = M_D_CPU1_SA_DQ<4>
  VSS4  = GND
  DQ5_A  = M_D_CPU1_SA_DQ<5>
  VSS5  = GND
  DQ8_A  = M_D_CPU1_SA_DQ<8>
  VSS6  = GND
  DQ9_A  = M_D_CPU1_SA_DQ<9>
  VSS7  = GND
  DQS1_A_T  = M_D_CPU1_SA_DQS_DP<1>
  DQS1_A_C  = M_D_CPU1_SA_DQS_DN<1>
  VSS8  = GND
  DQ12_A  = M_D_CPU1_SA_DQ<12>
  VSS9  = GND
  DQ13_A  = M_D_CPU1_SA_DQ<13>
  VSS10  = GND
  DQ16_A  = M_D_CPU1_SA_DQ<16>
  VSS11  = GND
  DQ17_A  = M_D_CPU1_SA_DQ<17>
  VSS12  = GND
  DQS2_A_T  = M_D_CPU1_SA_DQS_DP<2>
  DQS2_A_C  = M_D_CPU1_SA_DQS_DN<2>
  VSS13  = GND
  DQ20_A  = M_D_CPU1_SA_DQ<20>
  VSS14  = GND
  DQ21_A  = M_D_CPU1_SA_DQ<21>
  VSS15  = GND
  DQ24_A  = M_D_CPU1_SA_DQ<24>
  VSS16  = GND
  DQ25_A  = M_D_CPU1_SA_DQ<25>
  VSS17  = GND
  DQS3_A_T  = M_D_CPU1_SA_DQS_DP<3>
  DQS3_A_C  = M_D_CPU1_SA_DQS_DN<3>
  VSS18  = GND
  DQ28_A  = M_D_CPU1_SA_DQ<28>
  VSS19  = GND
  DQ29_A  = M_D_CPU1_SA_DQ<29>
  VSS20  = GND
  CB0_A  = M_D_CPU1_SA_CB<0>
  VSS21  = GND
  CB1_A  = M_D_CPU1_SA_CB<1>
  VSS22  = GND
  DQS4_A_T  = M_D_CPU1_SA_DQS_DP<4>
  DQS4_A_C  = M_D_CPU1_SA_DQS_DN<4>
  VSS23  = GND
  CB4_A  = M_D_CPU1_SA_CB<4>
  VSS24  = GND
  CB5_A  = M_D_CPU1_SA_CB<5>
  VSS25  = GND
  ALERT_N  = M_D_CPU1_ALERT_N
  VSS26  = GND
  CS0_A_N  = M_D_CPU1_SA_CS_N<0>
  VSS27  = GND
  CA0_A  = M_D_CPU1_SA_CA<0>
  VSS28  = GND
  CA2_A  = M_D_CPU1_SA_CA<2>
  VSS29  = GND
  CA4_A  = M_D_CPU1_SA_CA<4>
  VSS30  = GND
  CA6_A  = M_D_CPU1_SA_CA<6>
  VSS31  = GND
  PAR_A  = M_D_CPU1_SA_PAR
  VSS32  = GND
  CA0_B  = M_D_CPU1_SB_CA<0>
  VSS33  = GND
  CA2_B  = M_D_CPU1_SB_CA<2>
  VSS34  = GND
  CA4_B  = M_D_CPU1_SB_CA<4>
  VSS35  = GND
  CA6_B  = M_D_CPU1_SB_CA<6>
  VSS36  = GND
  CS0_B_N  = M_D_CPU1_SB_CS_N<0>
  VSS37  = GND
  \lbd||rsp_a_n\  = M_D_CPU1_SA_RSP<0>
  \lbs||rsp_b_n\  = M_D_CPU1_SB_RSP<0>
  VSS38  = GND
  CB4_B  = M_D_CPU1_SB_CB<4>
  VSS39  = GND
  CB5_B  = M_D_CPU1_SB_CB<5>
  VSS40  = GND
  \dqs9_b_t||tdqs9_b_t||dbi4_b_n\  = M_D_CPU1_SB_DQS_DP<9>
  \dqs9_b_c||tdqs9_b_c\  = M_D_CPU1_SB_DQS_DN<9>
  VSS41  = GND
  CB0_B  = M_D_CPU1_SB_CB<0>
  VSS42  = GND
  CB1_B  = M_D_CPU1_SB_CB<1>
  VSS43  = GND
  DQ0_B  = M_D_CPU1_SB_DQ<0>
  VSS44  = GND
  DQ1_B  = M_D_CPU1_SB_DQ<1>
  VSS45  = GND
  DQS0_B_T  = M_D_CPU1_SB_DQS_DP<0>
  DQS0_B_C  = M_D_CPU1_SB_DQS_DN<0>
  VSS46  = GND
  DQ4_B  = M_D_CPU1_SB_DQ<4>
  VSS47  = GND
  DQ5_B  = M_D_CPU1_SB_DQ<5>
  VSS48  = GND
  DQ8_B  = M_D_CPU1_SB_DQ<8>
  VSS49  = GND
  DQ9_B  = M_D_CPU1_SB_DQ<9>
  VSS50  = GND
  DQS1_B_T  = M_D_CPU1_SB_DQS_DP<1>
  DQS1_B_C  = M_D_CPU1_SB_DQS_DN<1>
  VSS51  = GND
  DQ12_B  = M_D_CPU1_SB_DQ<12>
  VSS52  = GND
  DQ13_B  = M_D_CPU1_SB_DQ<13>
  VSS53  = GND
  DQ16_B  = M_D_CPU1_SB_DQ<16>
  VSS54  = GND
  DQ17_B  = M_D_CPU1_SB_DQ<17>
  VSS55  = GND
  DQS2_B_T  = M_D_CPU1_SB_DQS_DP<2>
  DQS2_B_C  = M_D_CPU1_SB_DQS_DN<2>
  VSS56  = GND
  DQ20_B  = M_D_CPU1_SB_DQ<20>
  VSS57  = GND
  DQ21_B  = M_D_CPU1_SB_DQ<21>
  VSS58  = GND
  DQ24_B  = M_D_CPU1_SB_DQ<24>
  VSS59  = GND
  DQ25_B  = M_D_CPU1_SB_DQ<25>
  VSS60  = GND
  DQS3_B_T  = M_D_CPU1_SB_DQS_DP<3>
  DQS3_B_C  = M_D_CPU1_SB_DQS_DN<3>
  VSS61  = GND
  DQ28_B  = M_D_CPU1_SB_DQ<28>
  VSS62  = GND
  DQ29_B  = M_D_CPU1_SB_DQ<29>
  VSS63  = GND
  RFU1  = NC
  VIN_BULK1  = P12V_MEM_CPU1
  VIN_BULK2  = P12V_MEM_CPU1
  \pwr_good||fail_n\  = PWRGD_CHD_CPU1_DIMM
  HAS  = PD_CHD_CPU1_DIMM_SAA
  RFU2  = NC
  RFU3  = NC
  VSS64  = GND
  DQ2_A  = M_D_CPU1_SA_DQ<2>
  VSS65  = GND
  DQ3_A  = M_D_CPU1_SA_DQ<3>
  VSS66  = GND
  \dqs5_a_c||tdqs5_a_c||dqs5_a_t||tdqs5_a_t\  = M_D_CPU1_SA_DQS_DN<5>
  \dqs5_a_t||tdqs5_a_t\  = M_D_CPU1_SA_DQS_DP<5>
  VSS67  = GND
  DQ6_A  = M_D_CPU1_SA_DQ<6>
  VSS68  = GND
  DQ7_A  = M_D_CPU1_SA_DQ<7>
  VSS69  = GND
  DQ10_A  = M_D_CPU1_SA_DQ<10>
  VSS70  = GND
  DQ11_A  = M_D_CPU1_SA_DQ<11>
  VSS71  = GND
  \dqs6_a_c||tdqs6_a_c||dqs6_a_t||tdqs6_a_t\  = M_D_CPU1_SA_DQS_DN<6>
  \dqs6_a_t||tdqs6_a_t\  = M_D_CPU1_SA_DQS_DP<6>
  VSS72  = GND
  DQ14_A  = M_D_CPU1_SA_DQ<14>
  VSS73  = GND
  DQ15_A  = M_D_CPU1_SA_DQ<15>
  VSS74  = GND
  DQ18_A  = M_D_CPU1_SA_DQ<18>
  VSS75  = GND
  DQ19_A  = M_D_CPU1_SA_DQ<19>
  VSS76  = GND
  \dqs7_a_c||tdqs7_a_c\  = M_D_CPU1_SA_DQS_DN<7>
  \dqs7_a_t||tdqs7_a_t\  = M_D_CPU1_SA_DQS_DP<7>
  VSS77  = GND
  DQ22_A  = M_D_CPU1_SA_DQ<22>
  VSS78  = GND
  DQ23_A  = M_D_CPU1_SA_DQ<23>
  VSS79  = GND
  DQ26_A  = M_D_CPU1_SA_DQ<26>
  VSS80  = GND
  DQ27_A  = M_D_CPU1_SA_DQ<27>
  VSS81  = GND
  \dqs8_a_c||tdqs8_a_c\  = M_D_CPU1_SA_DQS_DN<8>
  \dqs8_a_t||tdqs8_a_t\  = M_D_CPU1_SA_DQS_DP<8>
  VSS82  = GND
  DQ30_A  = M_D_CPU1_SA_DQ<30>
  VSS83  = GND
  DQ31_A  = M_D_CPU1_SA_DQ<31>
  VSS84  = GND
  CB2_A  = M_D_CPU1_SA_CB<2>
  VSS85  = GND
  CB3_A  = M_D_CPU1_SA_CB<3>
  VSS86  = GND
  \dqs9_a_c||tdqs9_a_c\  = M_D_CPU1_SA_DQS_DN<9>
  \dqs9_a_t||tdqs9_a_t\  = M_D_CPU1_SA_DQS_DP<9>
  VSS87  = GND
  CB6_A  = M_D_CPU1_SA_CB<6>
  VSS88  = GND
  CB7_A  = M_D_CPU1_SA_CB<7>
  VSS89  = GND
  RESET_N  = M_D_CPU1_RESET_N
  VSS90  = GND
  CS1_A_N  = M_D_CPU1_SA_CS_N<1>
  VSS91  = GND
  CA1_A  = M_D_CPU1_SA_CA<1>
  VSS92  = GND
  CA3_A  = M_D_CPU1_SA_CA<3>
  VSS93  = GND
  CA5_A  = M_D_CPU1_SA_CA<5>
  VSS94  = GND
  CK_T  = M_D_CPU1_CLK_DP<0>
  CK_C  = M_D_CPU1_CLK_DN<0>
  VSS95  = GND
  RFU4  = NC
  CA1_B  = M_D_CPU1_SB_CA<1>
  VSS96  = GND
  CA3_B  = M_D_CPU1_SB_CA<3>
  VSS97  = GND
  CA5_B  = M_D_CPU1_SB_CA<5>
  VSS98  = GND
  PAR_B  = M_D_CPU1_SB_PAR
  VSS99  = GND
  CS1_B_N  = M_D_CPU1_SB_CS_N<1>
  VSS100  = GND
  RFU5  = NC
  RFU6  = NC
  VSS101  = GND
  CB6_B  = M_D_CPU1_SB_CB<6>
  VSS102  = GND
  CB7_B  = M_D_CPU1_SB_CB<7>
  VSS103  = GND
  DQS4_B_C  = M_D_CPU1_SB_DQS_DN<4>
  DQS4_B_T  = M_D_CPU1_SB_DQS_DP<4>
  VSS104  = GND
  CB2_B  = M_D_CPU1_SB_CB<2>
  VSS105  = GND
  CB3_B  = M_D_CPU1_SB_CB<3>
  VSS106  = GND
  DQ2_B  = M_D_CPU1_SB_DQ<2>
  VSS107  = GND
  DQ3_B  = M_D_CPU1_SB_DQ<3>
  VSS108  = GND
  \dqs5_b_c||tdqs5_b_c\  = M_D_CPU1_SB_DQS_DN<5>
  \dqs5_b_t||tdqs5_b_t\  = M_D_CPU1_SB_DQS_DP<5>
  VSS109  = GND
  DQ6_B  = M_D_CPU1_SB_DQ<6>
  VSS110  = GND
  DQ7_B  = M_D_CPU1_SB_DQ<7>
  VSS111  = GND
  DQ10_B  = M_D_CPU1_SB_DQ<10>
  VSS112  = GND
  DQ11_B  = M_D_CPU1_SB_DQ<11>
  VSS113  = GND
  \dqs6_b_c||tdqs6_b_c\  = M_D_CPU1_SB_DQS_DN<6>
  \dqs6_b_t||tdqs6_b_t\  = M_D_CPU1_SB_DQS_DP<6>
  VSS114  = GND
  DQ14_B  = M_D_CPU1_SB_DQ<14>
  VSS115  = GND
  DQ15_B  = M_D_CPU1_SB_DQ<15>
  VSS116  = GND
  DQ18_B  = M_D_CPU1_SB_DQ<18>
  VSS117  = GND
  DQ19_B  = M_D_CPU1_SB_DQ<19>
  VSS118  = GND
  \dqs7_b_c||tdqs7_b_c\  = M_D_CPU1_SB_DQS_DN<7>
  \dqs7_b_t||tdqs7_b_t\  = M_D_CPU1_SB_DQS_DP<7>
  VSS119  = GND
  DQ22_B  = M_D_CPU1_SB_DQ<22>
  VSS120  = GND
  DQ23_B  = M_D_CPU1_SB_DQ<23>
  VSS121  = GND
  DQ26_B  = M_D_CPU1_SB_DQ<26>
  VSS122  = GND
  DQ27_B  = M_D_CPU1_SB_DQ<27>
  VSS123  = GND
  \dqs8_b_c||tdqs8_b_c\  = M_D_CPU1_SB_DQS_DN<8>
  \dqs8_b_t||tdqs8_b_t\  = M_D_CPU1_SB_DQS_DP<8>
  VSS124  = GND
  DQ30_B  = M_D_CPU1_SB_DQ<30>
  VSS125  = GND
  DQ31_B  = M_D_CPU1_SB_DQ<31>
  VSS126  = GND
  G1  = GND
  G2  = GND
  G3  = GND

(kicad_pcb
	(version 20260206)
	(generator "pcbnew")
	(generator_version "10.0")
	(general
		(thickness 1.6)
		(legacy_teardrops no)
	)
	(paper "A4")
	(title_block
		(title "04192023_DAF0TMB3IC0_F0TG_MB_C_brd_V02_OCP.brd")
		(comment 1 "Grand Teton / footprint 3579 of 8354 (J30), pads 93-138 of 291")
	)
	(layers
		(0 "F.Cu" signal "TOP")
		(4 "In1.Cu" signal "GND")
		(6 "In2.Cu" signal "IN1")
		(8 "In3.Cu" signal "GND1")
		(10 "In4.Cu" signal "IN2")
		(12 "In5.Cu" signal "GND2")
		(14 "In6.Cu" signal "IN3")
		(16 "In7.Cu" signal "GND3")
		(18 "In8.Cu" signal "VCC")
		(20 "In9.Cu" signal "VCC1")
		(22 "In10.Cu" signal "GND4")
		(24 "In11.Cu" signal "IN4")
		(26 "In12.Cu" signal "GND5")
		(28 "In13.Cu" signal "IN5")
		(30 "In14.Cu" signal "GND6")
		(32 "In15.Cu" signal "IN6")
		(34 "In16.Cu" signal "GND7")
		(2 "B.Cu" signal "BOTTOM")
		(9 "F.Adhes" user "F.Adhesive")
		(11 "B.Adhes" user "B.Adhesive")
		(13 "F.Paste" user "Package Geometry/Pastemask Top")
		(15 "B.Paste" user "Package Geometry/Pastemask Bottom")
		(5 "F.SilkS" user "Ref Des/Silkscreen Top")
		(7 "B.SilkS" user "Ref Des/Silkscreen Bottom")
		(1 "F.Mask" user "Board Geometry/Soldermask Top")
		(3 "B.Mask" user "Board Geometry/Soldermask Bottom")
		(17 "Dwgs.User" user "User.Drawings")
		(19 "Cmts.User" user "User.Comments")
		(21 "Eco1.User" user "User.Eco1")
		(23 "Eco2.User" user "User.Eco2")
		(25 "Edge.Cuts" user "Board Geometry/Outline")
		(27 "Margin" user)
		(31 "F.CrtYd" user "Package Geometry/Place Bound Top")
		(29 "B.CrtYd" user "Package Geometry/Place Bound Bottom")
		(35 "F.Fab" user "Ref Des/Assembly Top")
		(33 "B.Fab" user "Ref Des/Assembly Bottom")
	)
	(footprint ""
		(layer "F.Cu")
		(at 34.74593 -255.560322 180)
		(property "Reference" "J30"
			(at 3.12293 -81.850992 0)
			(unlocked yes)
			(layer "F.SilkS")
			(effects
				(font
					(size 0.7874 0.5842)
					(thickness 0.1524)
				)
			)
		)
		(property "Value" ""
			(at 0 0 180)
			(layer "F.Fab")
			(effects
				(font
					(size 1.27 1.27)
				)
			)
		)
		(duplicate_pad_numbers_are_jumpers no)
		(pad "93" smd rect
			(at -2.050034 19.975068 90)
			(size 0.519938 1.4986)
			(layers "F.Cu" "F.Mask" "F.Paste")
			(net "M_D_CPU1_SB_DQS_DP<9>")
		)
		(pad "94" smd rect
			(at -2.050034 20.824952 90)
			(size 0.519938 1.4986)
			(layers "F.Cu" "F.Mask" "F.Paste")
			(net "M_D_CPU1_SB_DQS_DN<9>")
		)
		(pad "95" smd rect
			(at -2.050034 21.67509 90)
			(size 0.519938 1.4986)
			(layers "F.Cu" "F.Mask" "F.Paste")
			(net "GND")
		)
		(pad "96" smd rect
			(at -2.050034 22.524974 90)
			(size 0.519938 1.4986)
			(layers "F.Cu" "F.Mask" "F.Paste")
			(net "M_D_CPU1_SB_CB<0>")
		)
		(pad "97" smd rect
			(at -2.050034 23.375112 90)
			(size 0.519938 1.4986)
			(layers "F.Cu" "F.Mask" "F.Paste")
			(net "GND")
		)
		(pad "98" smd rect
			(at -2.050034 24.224996 90)
			(size 0.519938 1.4986)
			(layers "F.Cu" "F.Mask" "F.Paste")
			(net "M_D_CPU1_SB_CB<1>")
		)
		(pad "99" smd rect
			(at -2.050034 25.07488 90)
			(size 0.519938 1.4986)
			(layers "F.Cu" "F.Mask" "F.Paste")
			(net "GND")
		)
		(pad "100" smd rect
			(at -2.050034 25.925018 90)
			(size 0.519938 1.4986)
			(layers "F.Cu" "F.Mask" "F.Paste")
			(net "M_D_CPU1_SB_DQ<0>")
		)
		(pad "101" smd rect
			(at -2.050034 26.774902 90)
			(size 0.519938 1.4986)
			(layers "F.Cu" "F.Mask" "F.Paste")
			(net "GND")
		)
		(pad "102" smd rect
			(at -2.050034 27.62504 90)
			(size 0.519938 1.4986)
			(layers "F.Cu" "F.Mask" "F.Paste")
			(net "M_D_CPU1_SB_DQ<1>")
		)
		(pad "103" smd rect
			(at -2.050034 28.474924 90)
			(size 0.519938 1.4986)
			(layers "F.Cu" "F.Mask" "F.Paste")
			(net "GND")
		)
		(pad "104" smd rect
			(at -2.050034 29.325062 90)
			(size 0.519938 1.4986)
			(layers "F.Cu" "F.Mask" "F.Paste")
			(net "M_D_CPU1_SB_DQS_DP<0>")
		)
		(pad "105" smd rect
			(at -2.050034 30.174946 90)
			(size 0.519938 1.4986)
			(layers "F.Cu" "F.Mask" "F.Paste")
			(net "M_D_CPU1_SB_DQS_DN<0>")
		)
		(pad "106" smd rect
			(at -2.050034 31.025084 90)
			(size 0.519938 1.4986)
			(layers "F.Cu" "F.Mask" "F.Paste")
			(net "GND")
		)
		(pad "107" smd rect
			(at -2.050034 31.874968 90)
			(size 0.519938 1.4986)
			(layers "F.Cu" "F.Mask" "F.Paste")
			(net "M_D_CPU1_SB_DQ<4>")
		)
		(pad "108" smd rect
			(at -2.050034 32.725106 90)
			(size 0.519938 1.4986)
			(layers "F.Cu" "F.Mask" "F.Paste")
			(net "GND")
		)
		(pad "109" smd rect
			(at -2.050034 33.57499 90)
			(size 0.519938 1.4986)
			(layers "F.Cu" "F.Mask" "F.Paste")
			(net "M_D_CPU1_SB_DQ<5>")
		)
		(pad "110" smd rect
			(at -2.050034 34.425128 90)
			(size 0.519938 1.4986)
			(layers "F.Cu" "F.Mask" "F.Paste")
			(net "GND")
		)
		(pad "111" smd rect
			(at -2.050034 35.275012 90)
			(size 0.519938 1.4986)
			(layers "F.Cu" "F.Mask" "F.Paste")
			(net "M_D_CPU1_SB_DQ<8>")
		)
		(pad "112" smd rect
			(at -2.050034 36.124896 90)
			(size 0.519938 1.4986)
			(layers "F.Cu" "F.Mask" "F.Paste")
			(net "GND")
		)
		(pad "113" smd rect
			(at -2.050034 36.975034 90)
			(size 0.519938 1.4986)
			(layers "F.Cu" "F.Mask" "F.Paste")
			(net "M_D_CPU1_SB_DQ<9>")
		)
		(pad "114" smd rect
			(at -2.050034 37.824918 90)
			(size 0.519938 1.4986)
			(layers "F.Cu" "F.Mask" "F.Paste")
			(net "GND")
		)
		(pad "115" smd rect
			(at -2.050034 38.675056 90)
			(size 0.519938 1.4986)
			(layers "F.Cu" "F.Mask" "F.Paste")
			(net "M_D_CPU1_SB_DQS_DP<1>")
		)
		(pad "116" smd rect
			(at -2.050034 39.52494 90)
			(size 0.519938 1.4986)
			(layers "F.Cu" "F.Mask" "F.Paste")
			(net "M_D_CPU1_SB_DQS_DN<1>")
		)
		(pad "117" smd rect
			(at -2.050034 40.375078 90)
			(size 0.519938 1.4986)
			(layers "F.Cu" "F.Mask" "F.Paste")
			(net "GND")
		)
		(pad "118" smd rect
			(at -2.050034 41.224962 90)
			(size 0.519938 1.4986)
			(layers "F.Cu" "F.Mask" "F.Paste")
			(net "M_D_CPU1_SB_DQ<12>")
		)
		(pad "119" smd rect
			(at -2.050034 42.0751 90)
			(size 0.519938 1.4986)
			(layers "F.Cu" "F.Mask" "F.Paste")
			(net "GND")
		)
		(pad "120" smd rect
			(at -2.050034 42.924984 90)
			(size 0.519938 1.4986)
			(layers "F.Cu" "F.Mask" "F.Paste")
			(net "M_D_CPU1_SB_DQ<13>")
		)
		(pad "121" smd rect
			(at -2.050034 43.775122 90)
			(size 0.519938 1.4986)
			(layers "F.Cu" "F.Mask" "F.Paste")
			(net "GND")
		)
		(pad "122" smd rect
			(at -2.050034 44.625006 90)
			(size 0.519938 1.4986)
			(layers "F.Cu" "F.Mask" "F.Paste")
			(net "M_D_CPU1_SB_DQ<16>")
		)
		(pad "123" smd rect
			(at -2.050034 45.47489 90)
			(size 0.519938 1.4986)
			(layers "F.Cu" "F.Mask" "F.Paste")
			(net "GND")
		)
		(pad "124" smd rect
			(at -2.050034 46.325028 90)
			(size 0.519938 1.4986)
			(layers "F.Cu" "F.Mask" "F.Paste")
			(net "M_D_CPU1_SB_DQ<17>")
		)
		(pad "125" smd rect
			(at -2.050034 47.174912 90)
			(size 0.519938 1.4986)
			(layers "F.Cu" "F.Mask" "F.Paste")
			(net "GND")
		)
		(pad "126" smd rect
			(at -2.050034 48.02505 90)
			(size 0.519938 1.4986)
			(layers "F.Cu" "F.Mask" "F.Paste")
			(net "M_D_CPU1_SB_DQS_DP<2>")
		)
		(pad "127" smd rect
			(at -2.050034 48.874934 90)
			(size 0.519938 1.4986)
			(layers "F.Cu" "F.Mask" "F.Paste")
			(net "M_D_CPU1_SB_DQS_DN<2>")
		)
		(pad "128" smd rect
			(at -2.050034 49.725072 90)
			(size 0.519938 1.4986)
			(layers "F.Cu" "F.Mask" "F.Paste")
			(net "GND")
		)
		(pad "129" smd rect
			(at -2.050034 50.574956 90)
			(size 0.519938 1.4986)
			(layers "F.Cu" "F.Mask" "F.Paste")
			(net "M_D_CPU1_SB_DQ<20>")
		)
		(pad "130" smd rect
			(at -2.050034 51.425094 90)
			(size 0.519938 1.4986)
			(layers "F.Cu" "F.Mask" "F.Paste")
			(net "GND")
		)
		(pad "131" smd rect
			(at -2.050034 52.274978 90)
			(size 0.519938 1.4986)
			(layers "F.Cu" "F.Mask" "F.Paste")
			(net "M_D_CPU1_SB_DQ<21>")
		)
		(pad "132" smd rect
			(at -2.050034 53.125116 90)
			(size 0.519938 1.4986)
			(layers "F.Cu" "F.Mask" "F.Paste")
			(net "GND")
		)
		(pad "133" smd rect
			(at -2.050034 53.975 90)
			(size 0.519938 1.4986)
			(layers "F.Cu" "F.Mask" "F.Paste")
			(net "M_D_CPU1_SB_DQ<24>")
		)
		(pad "134" smd rect
			(at -2.050034 54.824884 90)
			(size 0.519938 1.4986)
			(layers "F.Cu" "F.Mask" "F.Paste")
			(net "GND")
		)
		(pad "135" smd rect
			(at -2.050034 55.675022 90)
			(size 0.519938 1.4986)
			(layers "F.Cu" "F.Mask" "F.Paste")
			(net "M_D_CPU1_SB_DQ<25>")
		)
		(pad "136" smd rect
			(at -2.050034 56.524906 90)
			(size 0.519938 1.4986)
			(layers "F.Cu" "F.Mask" "F.Paste")
			(net "GND")
		)
		(pad "137" smd rect
			(at -2.050034 57.375044 90)
			(size 0.519938 1.4986)
			(layers "F.Cu" "F.Mask" "F.Paste")
			(net "M_D_CPU1_SB_DQS_DP<3>")
		)
		(pad "138" smd rect
			(at -2.050034 58.224928 90)
			(size 0.519938 1.4986)
			(layers "F.Cu" "F.Mask" "F.Paste")
			(net "M_D_CPU1_SB_DQS_DN<3>")
		)
	)
)
